(kicad_pcb
	(version 20260206)
	(generator "pcbnew")
	(generator_version "10.0")
	(general
		(thickness 1.6)
		(legacy_teardrops no)
	)
	(paper "A4")
	(title_block
		(title "04192023_DAF0TMB3IC0_F0TG_MB_C_brd_V02_OCP.brd")
		(comment 1 "Grand Teton / footprints 8332-8338 of 8354")
	)
	(layers
		(0 "F.Cu" signal "TOP")
		(4 "In1.Cu" signal "GND")
		(6 "In2.Cu" signal "IN1")
		(8 "In3.Cu" signal "GND1")
		(10 "In4.Cu" signal "IN2")
		(12 "In5.Cu" signal "GND2")
		(14 "In6.Cu" signal "IN3")
		(16 "In7.Cu" signal "GND3")
		(18 "In8.Cu" signal "VCC")
		(20 "In9.Cu" signal "VCC1")
		(22 "In10.Cu" signal "GND4")
		(24 "In11.Cu" signal "IN4")
		(26 "In12.Cu" signal "GND5")
		(28 "In13.Cu" signal "IN5")
		(30 "In14.Cu" signal "GND6")
		(32 "In15.Cu" signal "IN6")
		(34 "In16.Cu" signal "GND7")
		(2 "B.Cu" signal "BOTTOM")
		(9 "F.Adhes" user "F.Adhesive")
		(11 "B.Adhes" user "B.Adhesive")
		(13 "F.Paste" user "Package Geometry/Pastemask Top")
		(15 "B.Paste" user "Package Geometry/Pastemask Bottom")
		(5 "F.SilkS" user "Ref Des/Silkscreen Top")
		(7 "B.SilkS" user "Ref Des/Silkscreen Bottom")
		(1 "F.Mask" user "Board Geometry/Soldermask Top")
		(3 "B.Mask" user "Board Geometry/Soldermask Bottom")
		(17 "Dwgs.User" user "User.Drawings")
		(19 "Cmts.User" user "User.Comments")
		(21 "Eco1.User" user "User.Eco1")
		(23 "Eco2.User" user "User.Eco2")
		(25 "Edge.Cuts" user "Board Geometry/Outline")
		(27 "Margin" user)
		(31 "F.CrtYd" user "Package Geometry/Place Bound Top")
		(29 "B.CrtYd" user "Package Geometry/Place Bound Bottom")
		(35 "F.Fab" user "Ref Des/Assembly Top")
		(33 "B.Fab" user "Ref Des/Assembly Bottom")
	)
	(footprint ""
		(layer "B.Cu")
		(at 419.263322 -416.899344 90)
		(property "Reference" "C6627"
			(at 0 0 90)
			(layer "B.SilkS")
			(hide yes)
			(effects
				(font
					(size 1.27 1.27)
				)
				(justify mirror)
			)
		)
		(property "Value" ""
			(at 0 0 90)
			(layer "B.Fab")
			(effects
				(font
					(size 1.27 1.27)
				)
				(justify mirror)
			)
		)
		(duplicate_pad_numbers_are_jumpers no)
		(fp_line
			(start 0.299974 -0.150114)
			(end -0.299974 -0.150114)
			(stroke
				(width 0.1)
				(type default)
			)
			(layer "B.Fab")
		)
		(fp_line
			(start -0.299974 -0.150114)
			(end -0.299974 0.150114)
			(stroke
				(width 0.1)
				(type default)
			)
			(layer "B.Fab")
		)
		(fp_line
			(start 0.299974 0.150114)
			(end 0.299974 -0.150114)
			(stroke
				(width 0.1)
				(type default)
			)
			(layer "B.Fab")
		)
		(fp_line
			(start -0.299974 0.150114)
			(end 0.299974 0.150114)
			(stroke
				(width 0.1)
				(type default)
			)
			(layer "B.Fab")
		)
		(pad "1" smd rect
			(at 0.2667 0 270)
			(size 0.3048 0.381)
			(layers "B.Cu" "B.Mask" "B.Paste")
			(net "P5E_CPU0_P3_TX_BUF_C_DP<15>")
		)
		(pad "2" smd rect
			(at -0.2667 0 270)
			(size 0.3048 0.381)
			(layers "B.Cu" "B.Mask" "B.Paste")
			(net "P5E_CPU0_P3_TX_BUF_DP<15>")
		)
	)
	(footprint ""
		(layer "B.Cu")
		(at 520.044426 -147.962874 90)
		(property "Reference" "X5"
			(at 0.989076 2.861564 270)
			(unlocked yes)
			(layer "B.SilkS")
			(effects
				(font
					(size 0.7874 0.5842)
					(thickness 0.1524)
				)
				(justify left mirror)
			)
		)
		(property "Value" ""
			(at 0 0 90)
			(layer "B.Fab")
			(effects
				(font
					(size 1.27 1.27)
				)
				(justify mirror)
			)
		)
		(property "Device Type" "TP_TDR_4P_FTS_TH-TP_TDR_4P_DIP,EMPTY,TP15"
			(at -1.30175 1.27 0)
			(unlocked yes)
			(layer "B.Fab")
			(hide yes)
			(effects
				(font
					(size 0.635 0.4064)
					(thickness 0.1524)
				)
				(justify mirror)
			)
		)
		(property "User Part Number" "N_A"
			(at -1.30175 1.27 0)
			(unlocked yes)
			(layer "Cmts.User")
			(hide yes)
			(effects
				(font
					(size 0.635 0.4064)
					(thickness 0.1524)
				)
				(justify mirror)
			)
		)
		(duplicate_pad_numbers_are_jumpers no)
		(fp_line
			(start 0 -1.27)
			(end 0 -0.635)
			(stroke
				(width 0.1524)
				(type default)
			)
			(layer "B.SilkS")
		)
		(fp_line
			(start -2.54 -1.27)
			(end 0 -1.27)
			(stroke
				(width 0.1524)
				(type default)
			)
			(layer "B.SilkS")
		)
		(fp_line
			(start -2.54 -1.1303)
			(end -2.54 -1.27)
			(stroke
				(width 0.1524)
				(type default)
			)
			(layer "B.SilkS")
		)
		(fp_line
			(start 0 0.635)
			(end 0 1.905)
			(stroke
				(width 0.1524)
				(type default)
			)
			(layer "B.SilkS")
		)
		(fp_line
			(start -2.54 1.4097)
			(end -2.54 1.1303)
			(stroke
				(width 0.1524)
				(type default)
			)
			(layer "B.SilkS")
		)
		(fp_line
			(start 0 3.175)
			(end 0 3.81)
			(stroke
				(width 0.1524)
				(type default)
			)
			(layer "B.SilkS")
		)
		(fp_line
			(start 0 3.81)
			(end -2.54 3.81)
			(stroke
				(width 0.1524)
				(type default)
			)
			(layer "B.SilkS")
		)
		(fp_line
			(start -2.54 3.81)
			(end -2.54 3.6703)
			(stroke
				(width 0.1524)
				(type default)
			)
			(layer "B.SilkS")
		)
		(fp_poly
			(pts
				(xy 2.285746 -0.762) (xy 2.285746 0.762) (xy 0.761746 0)
			)
			(stroke
				(width 0)
				(type default)
			)
			(fill yes)
			(layer "B.SilkS")
		)
		(fp_line
			(start 0 -1.27)
			(end 0 3.81)
			(stroke
				(width 0.1)
				(type default)
			)
			(layer "B.Fab")
		)
		(fp_line
			(start -2.54 -1.27)
			(end 0 -1.27)
			(stroke
				(width 0.1)
				(type default)
			)
			(layer "B.Fab")
		)
		(fp_line
			(start 0 3.81)
			(end -2.54 3.81)
			(stroke
				(width 0.1)
				(type default)
			)
			(layer "B.Fab")
		)
		(fp_line
			(start -2.54 3.81)
			(end -2.54 -1.27)
			(stroke
				(width 0.1)
				(type default)
			)
			(layer "B.Fab")
		)
		(fp_poly
			(pts
				(xy 0.761746 0) (xy 2.285746 -0.762) (xy 2.285746 0.762)
			)
			(stroke
				(width 0)
				(type default)
			)
			(fill yes)
			(layer "B.Fab")
		)
		(pad "1" thru_hole circle
			(at 0 0 270)
			(size 1.0033 1.0033)
			(drill 0.249936)
			(layers "*.Cu" "*.Mask")
			(remove_unused_layers no)
			(net "TDR_DIFF_80_IN4_DP")
			(clearance 0.10795)
			(padstack
				(mode front_inner_back)
				(layer "Inner"
					(shape circle)
					(size 0.8001 0.8001)
					(clearance 0.1524)
				)
				(layer "B.Cu"
					(shape circle)
					(size 1.0033 1.0033)
					(thermal_gap 0.10795)
					(clearance 0.10795)
				)
			)
		)
		(pad "2" thru_hole circle
			(at -2.54 0 270)
			(size 1.9939 1.9939)
			(drill 0.249936)
			(layers "*.Cu" "*.Mask")
			(remove_unused_layers no)
			(net "T1_GND")
			(clearance 0.10795)
			(padstack
				(mode front_inner_back)
				(layer "Inner"
					(shape circle)
					(size 0.8001 0.8001)
					(clearance 0.1524)
				)
				(layer "B.Cu"
					(shape circle)
					(size 1.9939 1.9939)
					(thermal_gap 0.10795)
					(clearance 0.10795)
				)
			)
		)
		(pad "3" thru_hole circle
			(at -2.54 2.54 270)
			(size 1.9939 1.9939)
			(drill 0.249936)
			(layers "*.Cu" "*.Mask")
			(remove_unused_layers no)
			(net "T1_GND")
			(clearance 0.10795)
			(padstack
				(mode front_inner_back)
				(layer "Inner"
					(shape circle)
					(size 0.8001 0.8001)
					(clearance 0.1524)
				)
				(layer "B.Cu"
					(shape circle)
					(size 1.9939 1.9939)
					(thermal_gap 0.10795)
					(clearance 0.10795)
				)
			)
		)
		(pad "4" thru_hole circle
			(at 0 2.54 270)
			(size 1.0033 1.0033)
			(drill 0.249936)
			(layers "*.Cu" "*.Mask")
			(remove_unused_layers no)
			(net "TDR_DIFF_80_IN4_DN")
			(clearance 0.10795)
			(padstack
				(mode front_inner_back)
				(layer "Inner"
					(shape circle)
					(size 0.8001 0.8001)
					(clearance 0.1524)
				)
				(layer "B.Cu"
					(shape circle)
					(size 1.0033 1.0033)
					(thermal_gap 0.10795)
					(clearance 0.10795)
				)
			)
		)
	)
	(footprint ""
		(layer "B.Cu")
		(at 103.672386 -261.179564 180)
		(property "Reference" "C2467"
			(at 0 0 0)
			(layer "B.SilkS")
			(hide yes)
			(effects
				(font
					(size 1.27 1.27)
				)
				(justify mirror)
			)
		)
		(property "Value" ""
			(at 0 0 0)
			(layer "B.Fab")
			(effects
				(font
					(size 1.27 1.27)
				)
				(justify mirror)
			)
		)
		(duplicate_pad_numbers_are_jumpers no)
		(fp_line
			(start 0.7874 0.4064)
			(end 0.7874 -0.4064)
			(stroke
				(width 0.1524)
				(type default)
			)
			(layer "B.SilkS")
		)
		(fp_line
			(start 0.7874 -0.4064)
			(end -0.7874 -0.4064)
			(stroke
				(width 0.1524)
				(type default)
			)
			(layer "B.SilkS")
		)
		(fp_line
			(start -0.7874 0.4064)
			(end 0.7874 0.4064)
			(stroke
				(width 0.1524)
				(type default)
			)
			(layer "B.SilkS")
		)
		(fp_line
			(start -0.7874 -0.4064)
			(end -0.7874 0.4064)
			(stroke
				(width 0.1524)
				(type default)
			)
			(layer "B.SilkS")
		)
		(fp_line
			(start 0.67945 0.3048)
			(end 0.67945 -0.305054)
			(stroke
				(width 0.1)
				(type default)
			)
			(layer "B.Fab")
		)
		(fp_line
			(start 0.67945 -0.305054)
			(end 0.12065 -0.305054)
			(stroke
				(width 0.1)
				(type default)
			)
			(layer "B.Fab")
		)
		(fp_line
			(start 0.12065 0.3048)
			(end 0.67945 0.3048)
			(stroke
				(width 0.1)
				(type default)
			)
			(layer "B.Fab")
		)
		(fp_line
			(start 0.12065 0.2794)
			(end 0.12065 0.3048)
			(stroke
				(width 0.1)
				(type default)
			)
			(layer "B.Fab")
		)
		(fp_line
			(start 0.12065 -0.2794)
			(end -0.12065 -0.2794)
			(stroke
				(width 0.1)
				(type default)
			)
			(layer "B.Fab")
		)
		(fp_line
			(start 0.12065 -0.305054)
			(end 0.12065 -0.2794)
			(stroke
				(width 0.1)
				(type default)
			)
			(layer "B.Fab")
		)
		(fp_line
			(start -0.120396 0.3048)
			(end -0.120396 0.2794)
			(stroke
				(width 0.1)
				(type default)
			)
			(layer "B.Fab")
		)
		(fp_line
			(start -0.120396 0.2794)
			(end 0.12065 0.2794)
			(stroke
				(width 0.1)
				(type default)
			)
			(layer "B.Fab")
		)
		(fp_line
			(start -0.12065 -0.2794)
			(end -0.12065 -0.3048)
			(stroke
				(width 0.1)
				(type default)
			)
			(layer "B.Fab")
		)
		(fp_line
			(start -0.12065 -0.3048)
			(end -0.67945 -0.3048)
			(stroke
				(width 0.1)
				(type default)
			)
			(layer "B.Fab")
		)
		(fp_line
			(start -0.67945 0.3048)
			(end -0.120396 0.3048)
			(stroke
				(width 0.1)
				(type default)
			)
			(layer "B.Fab")
		)
		(fp_line
			(start -0.67945 -0.3048)
			(end -0.67945 0.3048)
			(stroke
				(width 0.1)
				(type default)
			)
			(layer "B.Fab")
		)
		(pad "1" smd circle
			(at 0.40005 0)
			(size 0 0)
			(layers "B.Cu" "B.Mask" "B.Paste")
			(net "PVDDCR_SOC_P1")
		)
		(pad "2" smd circle
			(at -0.40005 0)
			(size 0 0)
			(layers "B.Cu" "B.Mask" "B.Paste")
			(net "GND")
		)
	)
	(footprint ""
		(layer "B.Cu")
		(at 415.006282 -395.148562 90)
		(property "Reference" "C789"
			(at 0 0 90)
			(layer "B.SilkS")
			(hide yes)
			(effects
				(font
					(size 1.27 1.27)
				)
				(justify mirror)
			)
		)
		(property "Value" ""
			(at 0 0 90)
			(layer "B.Fab")
			(effects
				(font
					(size 1.27 1.27)
				)
				(justify mirror)
			)
		)
		(duplicate_pad_numbers_are_jumpers no)
		(fp_line
			(start 0.299974 -0.150114)
			(end -0.299974 -0.150114)
			(stroke
				(width 0.1)
				(type default)
			)
			(layer "B.Fab")
		)
		(fp_line
			(start -0.299974 -0.150114)
			(end -0.299974 0.150114)
			(stroke
				(width 0.1)
				(type default)
			)
			(layer "B.Fab")
		)
		(fp_line
			(start 0.299974 0.150114)
			(end 0.299974 -0.150114)
			(stroke
				(width 0.1)
				(type default)
			)
			(layer "B.Fab")
		)
		(fp_line
			(start -0.299974 0.150114)
			(end 0.299974 0.150114)
			(stroke
				(width 0.1)
				(type default)
			)
			(layer "B.Fab")
		)
		(pad "1" smd rect
			(at 0.2667 0 270)
			(size 0.3048 0.381)
			(layers "B.Cu" "B.Mask" "B.Paste")
			(net "P0V9_CPU0_RT_2D")
		)
		(pad "2" smd rect
			(at -0.2667 0 270)
			(size 0.3048 0.381)
			(layers "B.Cu" "B.Mask" "B.Paste")
			(net "GND")
		)
	)
	(footprint ""
		(layer "B.Cu")
		(at 93.246194 -388.011162 -90)
		(property "Reference" "C316"
			(at 0 0 90)
			(layer "B.SilkS")
			(hide yes)
			(effects
				(font
					(size 1.27 1.27)
				)
				(justify mirror)
			)
		)
		(property "Value" ""
			(at 0 0 90)
			(layer "B.Fab")
			(effects
				(font
					(size 1.27 1.27)
				)
				(justify mirror)
			)
		)
		(duplicate_pad_numbers_are_jumpers no)
		(fp_line
			(start -0.299974 0.150114)
			(end 0.299974 0.150114)
			(stroke
				(width 0.1)
				(type default)
			)
			(layer "B.Fab")
		)
		(fp_line
			(start 0.299974 0.150114)
			(end 0.299974 -0.150114)
			(stroke
				(width 0.1)
				(type default)
			)
			(layer "B.Fab")
		)
		(fp_line
			(start -0.299974 -0.150114)
			(end -0.299974 0.150114)
			(stroke
				(width 0.1)
				(type default)
			)
			(layer "B.Fab")
		)
		(fp_line
			(start 0.299974 -0.150114)
			(end -0.299974 -0.150114)
			(stroke
				(width 0.1)
				(type default)
			)
			(layer "B.Fab")
		)
		(pad "1" smd rect
			(at 0.2667 0 90)
			(size 0.3048 0.381)
			(layers "B.Cu" "B.Mask" "B.Paste")
			(net "P0V9_CPU1_RT1_2A_2D")
		)
		(pad "2" smd rect
			(at -0.2667 0 90)
			(size 0.3048 0.381)
			(layers "B.Cu" "B.Mask" "B.Paste")
			(net "GND")
		)
	)
	(footprint ""
		(layer "B.Cu")
		(at 22.479 -365.76 180)
		(property "Reference" "C5022"
			(at 0 0 0)
			(layer "B.SilkS")
			(hide yes)
			(effects
				(font
					(size 1.27 1.27)
				)
				(justify mirror)
			)
		)
		(property "Value" ""
			(at 0 0 0)
			(layer "B.Fab")
			(effects
				(font
					(size 1.27 1.27)
				)
				(justify mirror)
			)
		)
		(duplicate_pad_numbers_are_jumpers no)
		(fp_line
			(start 0.7874 0.4064)
			(end 0.7874 -0.4064)
			(stroke
				(width 0.1524)
				(type default)
			)
			(layer "B.SilkS")
		)
		(fp_line
			(start 0.7874 -0.4064)
			(end -0.7874 -0.4064)
			(stroke
				(width 0.1524)
				(type default)
			)
			(layer "B.SilkS")
		)
		(fp_line
			(start -0.7874 0.4064)
			(end 0.7874 0.4064)
			(stroke
				(width 0.1524)
				(type default)
			)
			(layer "B.SilkS")
		)
		(fp_line
			(start -0.7874 -0.4064)
			(end -0.7874 0.4064)
			(stroke
				(width 0.1524)
				(type default)
			)
			(layer "B.SilkS")
		)
		(fp_line
			(start 0.67945 0.3048)
			(end 0.67945 -0.305054)
			(stroke
				(width 0.1)
				(type default)
			)
			(layer "B.Fab")
		)
		(fp_line
			(start 0.67945 -0.305054)
			(end 0.12065 -0.305054)
			(stroke
				(width 0.1)
				(type default)
			)
			(layer "B.Fab")
		)
		(fp_line
			(start 0.12065 0.3048)
			(end 0.67945 0.3048)
			(stroke
				(width 0.1)
				(type default)
			)
			(layer "B.Fab")
		)
		(fp_line
			(start 0.12065 0.2794)
			(end 0.12065 0.3048)
			(stroke
				(width 0.1)
				(type default)
			)
			(layer "B.Fab")
		)
		(fp_line
			(start 0.12065 -0.2794)
			(end -0.12065 -0.2794)
			(stroke
				(width 0.1)
				(type default)
			)
			(layer "B.Fab")
		)
		(fp_line
			(start 0.12065 -0.305054)
			(end 0.12065 -0.2794)
			(stroke
				(width 0.1)
				(type default)
			)
			(layer "B.Fab")
		)
		(fp_line
			(start -0.120396 0.3048)
			(end -0.120396 0.2794)
			(stroke
				(width 0.1)
				(type default)
			)
			(layer "B.Fab")
		)
		(fp_line
			(start -0.120396 0.2794)
			(end 0.12065 0.2794)
			(stroke
				(width 0.1)
				(type default)
			)
			(layer "B.Fab")
		)
		(fp_line
			(start -0.12065 -0.2794)
			(end -0.12065 -0.3048)
			(stroke
				(width 0.1)
				(type default)
			)
			(layer "B.Fab")
		)
		(fp_line
			(start -0.12065 -0.3048)
			(end -0.67945 -0.3048)
			(stroke
				(width 0.1)
				(type default)
			)
			(layer "B.Fab")
		)
		(fp_line
			(start -0.67945 0.3048)
			(end -0.120396 0.3048)
			(stroke
				(width 0.1)
				(type default)
			)
			(layer "B.Fab")
		)
		(fp_line
			(start -0.67945 -0.3048)
			(end -0.67945 0.3048)
			(stroke
				(width 0.1)
				(type default)
			)
			(layer "B.Fab")
		)
		(pad "1" smd circle
			(at 0.40005 0)
			(size 0 0)
			(layers "B.Cu" "B.Mask" "B.Paste")
			(net "GND")
		)
		(pad "2" smd circle
			(at -0.40005 0)
			(size 0 0)
			(layers "B.Cu" "B.Mask" "B.Paste")
			(net "PWRGD_PVDDCR_CPU1_P1")
		)
	)
	(footprint ""
		(layer "B.Cu")
		(at 163.819078 -390.560052 90)
		(property "Reference" "C412"
			(at 0 0 90)
			(layer "B.SilkS")
			(hide yes)
			(effects
				(font
					(size 1.27 1.27)
				)
				(justify mirror)
			)
		)
		(property "Value" ""
			(at 0 0 90)
			(layer "B.Fab")
			(effects
				(font
					(size 1.27 1.27)
				)
				(justify mirror)
			)
		)
		(duplicate_pad_numbers_are_jumpers no)
		(fp_line
			(start 0.7874 -0.4064)
			(end -0.7874 -0.4064)
			(stroke
				(width 0.1524)
				(type default)
			)
			(layer "B.SilkS")
		)
		(fp_line
			(start -0.7874 -0.4064)
			(end -0.7874 0.4064)
			(stroke
				(width 0.1524)
				(type default)
			)
			(layer "B.SilkS")
		)
		(fp_line
			(start 0.7874 0.4064)
			(end 0.7874 -0.4064)
			(stroke
				(width 0.1524)
				(type default)
			)
			(layer "B.SilkS")
		)
		(fp_line
			(start -0.7874 0.4064)
			(end 0.7874 0.4064)
			(stroke
				(width 0.1524)
				(type default)
			)
			(layer "B.SilkS")
		)
		(fp_line
			(start 0.67945 -0.305054)
			(end 0.12065 -0.305054)
			(stroke
				(width 0.1)
				(type default)
			)
			(layer "B.Fab")
		)
		(fp_line
			(start 0.12065 -0.305054)
			(end 0.12065 -0.2794)
			(stroke
				(width 0.1)
				(type default)
			)
			(layer "B.Fab")
		)
		(fp_line
			(start -0.12065 -0.3048)
			(end -0.67945 -0.3048)
			(stroke
				(width 0.1)
				(type default)
			)
			(layer "B.Fab")
		)
		(fp_line
			(start -0.67945 -0.3048)
			(end -0.67945 0.3048)
			(stroke
				(width 0.1)
				(type default)
			)
			(layer "B.Fab")
		)
		(fp_line
			(start 0.12065 -0.2794)
			(end -0.12065 -0.2794)
			(stroke
				(width 0.1)
				(type default)
			)
			(layer "B.Fab")
		)
		(fp_line
			(start -0.12065 -0.2794)
			(end -0.12065 -0.3048)
			(stroke
				(width 0.1)
				(type default)
			)
			(layer "B.Fab")
		)
		(fp_line
			(start 0.12065 0.2794)
			(end 0.12065 0.3048)
			(stroke
				(width 0.1)
				(type default)
			)
			(layer "B.Fab")
		)
		(fp_line
			(start -0.120396 0.2794)
			(end 0.12065 0.2794)
			(stroke
				(width 0.1)
				(type default)
			)
			(layer "B.Fab")
		)
		(fp_line
			(start 0.67945 0.3048)
			(end 0.67945 -0.305054)
			(stroke
				(width 0.1)
				(type default)
			)
			(layer "B.Fab")
		)
		(fp_line
			(start 0.12065 0.3048)
			(end 0.67945 0.3048)
			(stroke
				(width 0.1)
				(type default)
			)
			(layer "B.Fab")
		)
		(fp_line
			(start -0.120396 0.3048)
			(end -0.120396 0.2794)
			(stroke
				(width 0.1)
				(type default)
			)
			(layer "B.Fab")
		)
		(fp_line
			(start -0.67945 0.3048)
			(end -0.120396 0.3048)
			(stroke
				(width 0.1)
				(type default)
			)
			(layer "B.Fab")
		)
		(pad "1" smd circle
			(at 0.40005 0 270)
			(size 0 0)
			(layers "B.Cu" "B.Mask" "B.Paste")
			(net "P0V9_CPU1_RT2_2A")
		)
		(pad "2" smd circle
			(at -0.40005 0 270)
			(size 0 0)
			(layers "B.Cu" "B.Mask" "B.Paste")
			(net "GND")
		)
	)
)
